(kicad_pcb
	(version 20260206)
	(generator "pcbnew")
	(generator_version "10.0")
	(general
		(thickness 1.6)
		(legacy_teardrops no)
	)
	(paper "A4")
	(title_block
		(title "04192023_DAF0TMB3IC0_F0TG_MB_C_brd_V02_OCP.brd")
		(comment 1 "Grand Teton / footprint 802 of 8354 (J68), pads 227-291 of 291")
	)
	(layers
		(0 "F.Cu" signal "TOP")
		(4 "In1.Cu" signal "GND")
		(6 "In2.Cu" signal "IN1")
		(8 "In3.Cu" signal "GND1")
		(10 "In4.Cu" signal "IN2")
		(12 "In5.Cu" signal "GND2")
		(14 "In6.Cu" signal "IN3")
		(16 "In7.Cu" signal "GND3")
		(18 "In8.Cu" signal "VCC")
		(20 "In9.Cu" signal "VCC1")
		(22 "In10.Cu" signal "GND4")
		(24 "In11.Cu" signal "IN4")
		(26 "In12.Cu" signal "GND5")
		(28 "In13.Cu" signal "IN5")
		(30 "In14.Cu" signal "GND6")
		(32 "In15.Cu" signal "IN6")
		(34 "In16.Cu" signal "GND7")
		(2 "B.Cu" signal "BOTTOM")
		(9 "F.Adhes" user "F.Adhesive")
		(11 "B.Adhes" user "B.Adhesive")
		(13 "F.Paste" user "Package Geometry/Pastemask Top")
		(15 "B.Paste" user "Package Geometry/Pastemask Bottom")
		(5 "F.SilkS" user "Ref Des/Silkscreen Top")
		(7 "B.SilkS" user "Ref Des/Silkscreen Bottom")
		(1 "F.Mask" user "Board Geometry/Soldermask Top")
		(3 "B.Mask" user "Board Geometry/Soldermask Bottom")
		(17 "Dwgs.User" user "User.Drawings")
		(19 "Cmts.User" user "User.Comments")
		(21 "Eco1.User" user "User.Eco1")
		(23 "Eco2.User" user "User.Eco2")
		(25 "Edge.Cuts" user "Board Geometry/Outline")
		(27 "Margin" user)
		(31 "F.CrtYd" user "Package Geometry/Place Bound Top")
		(29 "B.CrtYd" user "Package Geometry/Place Bound Bottom")
		(35 "F.Fab" user "Ref Des/Assembly Top")
		(33 "B.Fab" user "Ref Des/Assembly Bottom")
	)
	(footprint ""
		(layer "F.Cu")
		(at 437.05018 -255.560068 180)
		(property "Reference" "J68"
			(at 1.32334 -81.844388 0)
			(unlocked yes)
			(layer "F.SilkS")
			(effects
				(font
					(size 0.7874 0.5842)
					(thickness 0.1524)
				)
			)
		)
		(property "Value" ""
			(at 0 0 180)
			(layer "F.Fab")
			(effects
				(font
					(size 1.27 1.27)
				)
			)
		)
		(duplicate_pad_numbers_are_jumpers no)
		(pad "227" smd rect
			(at 2.050034 11.474958 90)
			(size 0.519938 1.4986)
			(layers "F.Cu" "F.Mask" "F.Paste")
			(net "M_J_CPU0_SB_PAR")
		)
		(pad "228" smd rect
			(at 2.050034 12.325096 90)
			(size 0.519938 1.4986)
			(layers "F.Cu" "F.Mask" "F.Paste")
			(net "GND")
		)
		(pad "229" smd rect
			(at 2.050034 13.17498 90)
			(size 0.519938 1.4986)
			(layers "F.Cu" "F.Mask" "F.Paste")
			(net "M_J_CPU0_SB_CS_N<1>")
		)
		(pad "230" smd rect
			(at 2.050034 14.025118 90)
			(size 0.519938 1.4986)
			(layers "F.Cu" "F.Mask" "F.Paste")
			(net "GND")
		)
		(pad "231" smd rect
			(at 2.050034 14.875002 90)
			(size 0.519938 1.4986)
			(layers "F.Cu" "F.Mask" "F.Paste")
			(net "Net_2380")
		)
		(pad "232" smd rect
			(at 2.050034 15.724886 90)
			(size 0.519938 1.4986)
			(layers "F.Cu" "F.Mask" "F.Paste")
			(net "Net_2381")
		)
		(pad "233" smd rect
			(at 2.050034 16.575024 90)
			(size 0.519938 1.4986)
			(layers "F.Cu" "F.Mask" "F.Paste")
			(net "GND")
		)
		(pad "234" smd rect
			(at 2.050034 17.424908 90)
			(size 0.519938 1.4986)
			(layers "F.Cu" "F.Mask" "F.Paste")
			(net "M_J_CPU0_SB_CB<6>")
		)
		(pad "235" smd rect
			(at 2.050034 18.275046 90)
			(size 0.519938 1.4986)
			(layers "F.Cu" "F.Mask" "F.Paste")
			(net "GND")
		)
		(pad "236" smd rect
			(at 2.050034 19.12493 90)
			(size 0.519938 1.4986)
			(layers "F.Cu" "F.Mask" "F.Paste")
			(net "M_J_CPU0_SB_CB<7>")
		)
		(pad "237" smd rect
			(at 2.050034 19.975068 90)
			(size 0.519938 1.4986)
			(layers "F.Cu" "F.Mask" "F.Paste")
			(net "GND")
		)
		(pad "238" smd rect
			(at 2.050034 20.824952 90)
			(size 0.519938 1.4986)
			(layers "F.Cu" "F.Mask" "F.Paste")
			(net "M_J_CPU0_SB_DQS_DN<4>")
		)
		(pad "239" smd rect
			(at 2.050034 21.67509 90)
			(size 0.519938 1.4986)
			(layers "F.Cu" "F.Mask" "F.Paste")
			(net "M_J_CPU0_SB_DQS_DP<4>")
		)
		(pad "240" smd rect
			(at 2.050034 22.524974 90)
			(size 0.519938 1.4986)
			(layers "F.Cu" "F.Mask" "F.Paste")
			(net "GND")
		)
		(pad "241" smd rect
			(at 2.050034 23.375112 90)
			(size 0.519938 1.4986)
			(layers "F.Cu" "F.Mask" "F.Paste")
			(net "M_J_CPU0_SB_CB<2>")
		)
		(pad "242" smd rect
			(at 2.050034 24.224996 90)
			(size 0.519938 1.4986)
			(layers "F.Cu" "F.Mask" "F.Paste")
			(net "GND")
		)
		(pad "243" smd rect
			(at 2.050034 25.07488 90)
			(size 0.519938 1.4986)
			(layers "F.Cu" "F.Mask" "F.Paste")
			(net "M_J_CPU0_SB_CB<3>")
		)
		(pad "244" smd rect
			(at 2.050034 25.925018 90)
			(size 0.519938 1.4986)
			(layers "F.Cu" "F.Mask" "F.Paste")
			(net "GND")
		)
		(pad "245" smd rect
			(at 2.050034 26.774902 90)
			(size 0.519938 1.4986)
			(layers "F.Cu" "F.Mask" "F.Paste")
			(net "M_J_CPU0_SB_DQ<2>")
		)
		(pad "246" smd rect
			(at 2.050034 27.62504 90)
			(size 0.519938 1.4986)
			(layers "F.Cu" "F.Mask" "F.Paste")
			(net "GND")
		)
		(pad "247" smd rect
			(at 2.050034 28.474924 90)
			(size 0.519938 1.4986)
			(layers "F.Cu" "F.Mask" "F.Paste")
			(net "M_J_CPU0_SB_DQ<3>")
		)
		(pad "248" smd rect
			(at 2.050034 29.325062 90)
			(size 0.519938 1.4986)
			(layers "F.Cu" "F.Mask" "F.Paste")
			(net "GND")
		)
		(pad "249" smd rect
			(at 2.050034 30.174946 90)
			(size 0.519938 1.4986)
			(layers "F.Cu" "F.Mask" "F.Paste")
			(net "M_J_CPU0_SB_DQS_DN<5>")
		)
		(pad "250" smd rect
			(at 2.050034 31.025084 90)
			(size 0.519938 1.4986)
			(layers "F.Cu" "F.Mask" "F.Paste")
			(net "M_J_CPU0_SB_DQS_DP<5>")
		)
		(pad "251" smd rect
			(at 2.050034 31.874968 90)
			(size 0.519938 1.4986)
			(layers "F.Cu" "F.Mask" "F.Paste")
			(net "GND")
		)
		(pad "252" smd rect
			(at 2.050034 32.725106 90)
			(size 0.519938 1.4986)
			(layers "F.Cu" "F.Mask" "F.Paste")
			(net "M_J_CPU0_SB_DQ<6>")
		)
		(pad "253" smd rect
			(at 2.050034 33.57499 90)
			(size 0.519938 1.4986)
			(layers "F.Cu" "F.Mask" "F.Paste")
			(net "GND")
		)
		(pad "254" smd rect
			(at 2.050034 34.425128 90)
			(size 0.519938 1.4986)
			(layers "F.Cu" "F.Mask" "F.Paste")
			(net "M_J_CPU0_SB_DQ<7>")
		)
		(pad "255" smd rect
			(at 2.050034 35.275012 90)
			(size 0.519938 1.4986)
			(layers "F.Cu" "F.Mask" "F.Paste")
			(net "GND")
		)
		(pad "256" smd rect
			(at 2.050034 36.124896 90)
			(size 0.519938 1.4986)
			(layers "F.Cu" "F.Mask" "F.Paste")
			(net "M_J_CPU0_SB_DQ<10>")
		)
		(pad "257" smd rect
			(at 2.050034 36.975034 90)
			(size 0.519938 1.4986)
			(layers "F.Cu" "F.Mask" "F.Paste")
			(net "GND")
		)
		(pad "258" smd rect
			(at 2.050034 37.824918 90)
			(size 0.519938 1.4986)
			(layers "F.Cu" "F.Mask" "F.Paste")
			(net "M_J_CPU0_SB_DQ<11>")
		)
		(pad "259" smd rect
			(at 2.050034 38.675056 90)
			(size 0.519938 1.4986)
			(layers "F.Cu" "F.Mask" "F.Paste")
			(net "GND")
		)
		(pad "260" smd rect
			(at 2.050034 39.52494 90)
			(size 0.519938 1.4986)
			(layers "F.Cu" "F.Mask" "F.Paste")
			(net "M_J_CPU0_SB_DQS_DN<6>")
		)
		(pad "261" smd rect
			(at 2.050034 40.375078 90)
			(size 0.519938 1.4986)
			(layers "F.Cu" "F.Mask" "F.Paste")
			(net "M_J_CPU0_SB_DQS_DP<6>")
		)
		(pad "262" smd rect
			(at 2.050034 41.224962 90)
			(size 0.519938 1.4986)
			(layers "F.Cu" "F.Mask" "F.Paste")
			(net "GND")
		)
		(pad "263" smd rect
			(at 2.050034 42.0751 90)
			(size 0.519938 1.4986)
			(layers "F.Cu" "F.Mask" "F.Paste")
			(net "M_J_CPU0_SB_DQ<14>")
		)
		(pad "264" smd rect
			(at 2.050034 42.924984 90)
			(size 0.519938 1.4986)
			(layers "F.Cu" "F.Mask" "F.Paste")
			(net "GND")
		)
		(pad "265" smd rect
			(at 2.050034 43.775122 90)
			(size 0.519938 1.4986)
			(layers "F.Cu" "F.Mask" "F.Paste")
			(net "M_J_CPU0_SB_DQ<15>")
		)
		(pad "266" smd rect
			(at 2.050034 44.625006 90)
			(size 0.519938 1.4986)
			(layers "F.Cu" "F.Mask" "F.Paste")
			(net "GND")
		)
		(pad "267" smd rect
			(at 2.050034 45.47489 90)
			(size 0.519938 1.4986)
			(layers "F.Cu" "F.Mask" "F.Paste")
			(net "M_J_CPU0_SB_DQ<18>")
		)
		(pad "268" smd rect
			(at 2.050034 46.325028 90)
			(size 0.519938 1.4986)
			(layers "F.Cu" "F.Mask" "F.Paste")
			(net "GND")
		)
		(pad "269" smd rect
			(at 2.050034 47.174912 90)
			(size 0.519938 1.4986)
			(layers "F.Cu" "F.Mask" "F.Paste")
			(net "M_J_CPU0_SB_DQ<19>")
		)
		(pad "270" smd rect
			(at 2.050034 48.02505 90)
			(size 0.519938 1.4986)
			(layers "F.Cu" "F.Mask" "F.Paste")
			(net "GND")
		)
		(pad "271" smd rect
			(at 2.050034 48.874934 90)
			(size 0.519938 1.4986)
			(layers "F.Cu" "F.Mask" "F.Paste")
			(net "M_J_CPU0_SB_DQS_DN<7>")
		)
		(pad "272" smd rect
			(at 2.050034 49.725072 90)
			(size 0.519938 1.4986)
			(layers "F.Cu" "F.Mask" "F.Paste")
			(net "M_J_CPU0_SB_DQS_DP<7>")
		)
		(pad "273" smd rect
			(at 2.050034 50.574956 90)
			(size 0.519938 1.4986)
			(layers "F.Cu" "F.Mask" "F.Paste")
			(net "GND")
		)
		(pad "274" smd rect
			(at 2.050034 51.425094 90)
			(size 0.519938 1.4986)
			(layers "F.Cu" "F.Mask" "F.Paste")
			(net "M_J_CPU0_SB_DQ<22>")
		)
		(pad "275" smd rect
			(at 2.050034 52.274978 90)
			(size 0.519938 1.4986)
			(layers "F.Cu" "F.Mask" "F.Paste")
			(net "GND")
		)
		(pad "276" smd rect
			(at 2.050034 53.125116 90)
			(size 0.519938 1.4986)
			(layers "F.Cu" "F.Mask" "F.Paste")
			(net "M_J_CPU0_SB_DQ<23>")
		)
		(pad "277" smd rect
			(at 2.050034 53.975 90)
			(size 0.519938 1.4986)
			(layers "F.Cu" "F.Mask" "F.Paste")
			(net "GND")
		)
		(pad "278" smd rect
			(at 2.050034 54.824884 90)
			(size 0.519938 1.4986)
			(layers "F.Cu" "F.Mask" "F.Paste")
			(net "M_J_CPU0_SB_DQ<26>")
		)
		(pad "279" smd rect
			(at 2.050034 55.675022 90)
			(size 0.519938 1.4986)
			(layers "F.Cu" "F.Mask" "F.Paste")
			(net "GND")
		)
		(pad "280" smd rect
			(at 2.050034 56.524906 90)
			(size 0.519938 1.4986)
			(layers "F.Cu" "F.Mask" "F.Paste")
			(net "M_J_CPU0_SB_DQ<27>")
		)
		(pad "281" smd rect
			(at 2.050034 57.375044 90)
			(size 0.519938 1.4986)
			(layers "F.Cu" "F.Mask" "F.Paste")
			(net "GND")
		)
		(pad "282" smd rect
			(at 2.050034 58.224928 90)
			(size 0.519938 1.4986)
			(layers "F.Cu" "F.Mask" "F.Paste")
			(net "M_J_CPU0_SB_DQS_DN<8>")
		)
		(pad "283" smd rect
			(at 2.050034 59.075066 90)
			(size 0.519938 1.4986)
			(layers "F.Cu" "F.Mask" "F.Paste")
			(net "M_J_CPU0_SB_DQS_DP<8>")
		)
		(pad "284" smd rect
			(at 2.050034 59.92495 90)
			(size 0.519938 1.4986)
			(layers "F.Cu" "F.Mask" "F.Paste")
			(net "GND")
		)
		(pad "285" smd rect
			(at 2.050034 60.775088 90)
			(size 0.519938 1.4986)
			(layers "F.Cu" "F.Mask" "F.Paste")
			(net "M_J_CPU0_SB_DQ<30>")
		)
		(pad "286" smd rect
			(at 2.050034 61.624972 90)
			(size 0.519938 1.4986)
			(layers "F.Cu" "F.Mask" "F.Paste")
			(net "GND")
		)
		(pad "287" smd rect
			(at 2.050034 62.47511 90)
			(size 0.519938 1.4986)
			(layers "F.Cu" "F.Mask" "F.Paste")
			(net "M_J_CPU0_SB_DQ<31>")
		)
		(pad "288" smd rect
			(at 2.050034 63.324994 90)
			(size 0.519938 1.4986)
			(layers "F.Cu" "F.Mask" "F.Paste")
			(net "GND")
		)
		(pad "G1" thru_hole oval
			(at 0 -68.97497 90)
			(size 1.7272 3.4798)
			(drill oval 1.2192 2.4638)
			(layers "*.Cu" "*.Mask")
			(remove_unused_layers no)
			(net "GND")
			(clearance 0.127)
			(thermal_gap 0.127)
		)
		(pad "G2" thru_hole oval
			(at 0 3.875024 90)
			(size 1.7272 3.4798)
			(drill oval 1.2192 2.4638)
			(layers "*.Cu" "*.Mask")
			(remove_unused_layers no)
			(net "GND")
			(clearance 0.127)
			(thermal_gap 0.127)
		)
		(pad "G3" thru_hole oval
			(at 0 68.97497 90)
			(size 1.7272 3.4798)
			(drill oval 1.2192 2.4638)
			(layers "*.Cu" "*.Mask")
			(remove_unused_layers no)
			(net "GND")
			(clearance 0.127)
			(thermal_gap 0.127)
		)
	)
)
